(kicad_pcb
	(version 20241229)
	(generator "pcbnew")
	(generator_version "9.0")
	(general
		(thickness 1.6296)
		(legacy_teardrops no)
	)
	(paper "A3")
	(title_block
		(title "Thunderbolt to 10GbE adapter")
		(date "2026-04-21")
		(rev "1.1.0")
		(company "Antmicro Ltd")
		(comment 1 "www.antmicro.com")
		(comment 9 "footprints 464-467 of 703")
	)
	(layers
		(0 "F.Cu" signal)
		(4 "In1.Cu" signal)
		(6 "In2.Cu" signal)
		(8 "In3.Cu" signal)
		(10 "In4.Cu" signal)
		(12 "In5.Cu" signal)
		(14 "In6.Cu" signal)
		(2 "B.Cu" signal)
		(9 "F.Adhes" user "F.Adhesive")
		(11 "B.Adhes" user "B.Adhesive")
		(13 "F.Paste" user)
		(15 "B.Paste" user)
		(5 "F.SilkS" user "F.Silkscreen")
		(7 "B.SilkS" user "B.Silkscreen")
		(1 "F.Mask" user)
		(3 "B.Mask" user)
		(17 "Dwgs.User" user "User.Drawings")
		(19 "Cmts.User" user "User.Comments")
		(21 "Eco1.User" user "User.Eco1")
		(23 "Eco2.User" user "User.Eco2")
		(25 "Edge.Cuts" user)
		(27 "Margin" user)
		(31 "F.CrtYd" user "F.Courtyard")
		(29 "B.CrtYd" user "B.Courtyard")
		(35 "F.Fab" user)
		(33 "B.Fab" user)
	)
	(footprint "antmicro-footprints:Tag-Connect_TC2050-IDC-NL_2x5_P1.27mm"
		(layer "B.Cu")
		(at 126.02 77 -90)
		(property "Reference" "J8"
			(at 0.2 -3.38 90)
			(layer "B.SilkS")
			(effects
				(font
					(size 0.7 0.7)
					(thickness 0.15)
				)
				(justify left bottom mirror)
			)
		)
		(property "Value" "Tag-Connect_TC2050-IDC-NL_2x5_P1.27mm"
			(at 0 -4.4 90)
			(layer "B.Fab")
			(effects
				(font
					(size 0.7 0.7)
					(thickness 0.15)
				)
				(justify left bottom mirror)
			)
		)
		(property "Datasheet" "https://www.tag-connect.com/wp-content/uploads/bsk-pdf-manager/TC2050-IDC-NL_Datasheet_8.pdf"
			(at 0 0 90)
			(layer "B.Fab")
			(hide yes)
			(effects
				(font
					(size 1.27 1.27)
					(thickness 0.15)
				)
				(justify mirror)
			)
		)
		(property "Description" "Tag Connect 2x5 1.27mm terminal"
			(at 0 0 90)
			(layer "B.Fab")
			(hide yes)
			(effects
				(font
					(size 1.27 1.27)
					(thickness 0.15)
				)
				(justify mirror)
			)
		)
		(property "MPN" "TC2050-IDC-NL"
			(at 0 0 270)
			(unlocked yes)
			(layer "B.Fab")
			(hide yes)
			(effects
				(font
					(size 1 1)
					(thickness 0.15)
				)
				(justify mirror)
			)
		)
		(property "Manufacturer" "Tag Connect"
			(at 0 0 270)
			(unlocked yes)
			(layer "B.Fab")
			(hide yes)
			(effects
				(font
					(size 1 1)
					(thickness 0.15)
				)
				(justify mirror)
			)
		)
		(property "Author" "Antmicro"
			(at 0 0 270)
			(unlocked yes)
			(layer "B.Fab")
			(hide yes)
			(effects
				(font
					(size 1 1)
					(thickness 0.15)
				)
				(justify mirror)
			)
		)
		(property "License" "Apache-2.0"
			(at 0 0 270)
			(unlocked yes)
			(layer "B.Fab")
			(hide yes)
			(effects
				(font
					(size 1 1)
					(thickness 0.15)
				)
				(justify mirror)
			)
		)
		(sheetname "/X710 flash memory/")
		(sheetfile "flash_x710.kicad_sch")
		(attr exclude_from_pos_files exclude_from_bom dnp)
		(fp_line
			(start -2.2 2.05)
			(end 4.7 2.05)
			(stroke
				(width 0.15)
				(type solid)
			)
			(layer "B.SilkS")
		)
		(fp_line
			(start 4.7 2.05)
			(end 5.1 1.7)
			(stroke
				(width 0.15)
				(type solid)
			)
			(layer "B.SilkS")
		)
		(fp_line
			(start 5.1 1.7)
			(end 5.1 -1.7)
			(stroke
				(width 0.15)
				(type solid)
			)
			(layer "B.SilkS")
		)
		(fp_line
			(start -5.08 0.9)
			(end -2.2 2.05)
			(stroke
				(width 0.15)
				(type solid)
			)
			(layer "B.SilkS")
		)
		(fp_line
			(start -5.08 -0.8)
			(end -5.08 0.9)
			(stroke
				(width 0.15)
				(type solid)
			)
			(layer "B.SilkS")
		)
		(fp_line
			(start -3.101 -1.269)
			(end -3.101 -0.4)
			(stroke
				(width 0.15)
				(type solid)
			)
			(layer "B.SilkS")
		)
		(fp_line
			(start -2.3 -2.049)
			(end -5.08 -0.8)
			(stroke
				(width 0.15)
				(type solid)
			)
			(layer "B.SilkS")
		)
		(fp_line
			(start 4.7 -2.049)
			(end 5.1 -1.7)
			(stroke
				(width 0.15)
				(type solid)
			)
			(layer "B.SilkS")
		)
		(fp_line
			(start 4.7 -2.049)
			(end -2.3 -2.049)
			(stroke
				(width 0.15)
				(type solid)
			)
			(layer "B.SilkS")
		)
		(fp_line
			(start -2.3 2.3)
			(end 4.8 2.3)
			(stroke
				(width 0.05)
				(type solid)
			)
			(layer "B.CrtYd")
		)
		(fp_line
			(start 4.8 2.3)
			(end 5.32 1.8)
			(stroke
				(width 0.05)
				(type solid)
			)
			(layer "B.CrtYd")
		)
		(fp_line
			(start 5.32 1.8)
			(end 5.32 -1.8)
			(stroke
				(width 0.05)
				(type solid)
			)
			(layer "B.CrtYd")
		)
		(fp_line
			(start -5.33 1.1)
			(end -2.3 2.3)
			(stroke
				(width 0.05)
				(type solid)
			)
			(layer "B.CrtYd")
		)
		(fp_line
			(start -5.33 -1)
			(end -5.33 1.1)
			(stroke
				(width 0.05)
				(type solid)
			)
			(layer "B.CrtYd")
		)
		(fp_line
			(start -2.4 -2.29)
			(end -5.33 -1)
			(stroke
				(width 0.05)
				(type solid)
			)
			(layer "B.CrtYd")
		)
		(fp_line
			(start 4.8 -2.29)
			(end 5.32 -1.8)
			(stroke
				(width 0.05)
				(type solid)
			)
			(layer "B.CrtYd")
		)
		(fp_line
			(start 4.8 -2.29)
			(end -2.4 -2.29)
			(stroke
				(width 0.05)
				(type solid)
			)
			(layer "B.CrtYd")
		)
		(fp_text user "License: Apache-2.0"
			(at -6.223 -8.449 90)
			(layer "B.Fab")
			(effects
				(font
					(size 0.7 0.7)
					(thickness 0.15)
				)
				(justify left bottom mirror)
			)
		)
		(fp_text user "${REFERENCE}"
			(at -6.223 -6.049 90)
			(layer "B.Fab")
			(effects
				(font
					(size 0.7 0.7)
					(thickness 0.15)
				)
				(justify left bottom mirror)
			)
		)
		(fp_text user "Author: Antmicro"
			(at -6.223 -7.249 90)
			(layer "B.Fab")
			(effects
				(font
					(size 0.7 0.7)
					(thickness 0.15)
				)
				(justify left bottom mirror)
			)
		)
		(pad "" np_thru_hole circle
			(at -3.81 0 270)
			(size 0.9906 0.9906)
			(drill 0.9906)
			(layers "*.Cu" "*.Mask")
		)
		(pad "" np_thru_hole circle
			(at 3.809 -1.015 270)
			(size 0.9906 0.9906)
			(drill 0.9906)
			(layers "*.Cu" "*.Mask")
		)
		(pad "" np_thru_hole circle
			(at 3.809 1.016 270)
			(size 0.9906 0.9906)
			(drill 0.9906)
			(layers "*.Cu" "*.Mask")
		)
		(pad "1" connect circle
			(at -2.54 -0.634 270)
			(size 0.7874 0.7874)
			(layers "B.Cu" "B.Mask")
			(net 343 "/X710 flash memory/+3V3_FLASH")
			(pinfunction "3V3")
			(pintype "passive")
		)
		(pad "2" connect circle
			(at -1.27 -0.634 270)
			(size 0.7874 0.7874)
			(layers "B.Cu" "B.Mask")
			(net 350 "/X710 flash memory/FLASH.~{CE}")
			(pinfunction "SPI_CS")
			(pintype "passive")
		)
		(pad "3" connect circle
			(at 0 -0.634 270)
			(size 0.7874 0.7874)
			(layers "B.Cu" "B.Mask")
			(net 23 "GND")
			(pinfunction "GND")
			(pintype "passive")
		)
		(pad "4" connect circle
			(at 1.269 -0.634 270)
			(size 0.7874 0.7874)
			(layers "B.Cu" "B.Mask")
			(net 353 "/X710 flash memory/FLASH.CLK")
			(pinfunction "SPI_SCK")
			(pintype "passive")
		)
		(pad "5" connect circle
			(at 2.539 -0.634 270)
			(size 0.7874 0.7874)
			(layers "B.Cu" "B.Mask")
			(net 23 "GND")
			(pinfunction "GND")
			(pintype "passive")
		)
		(pad "6" connect circle
			(at 2.539 0.635 270)
			(size 0.7874 0.7874)
			(layers "B.Cu" "B.Mask")
			(net 351 "/X710 flash memory/FLASH.MISO")
			(pinfunction "SPI_MISO")
			(pintype "passive")
		)
		(pad "7" connect circle
			(at 1.269 0.635 270)
			(size 0.7874 0.7874)
			(layers "B.Cu" "B.Mask")
			(net 425 "unconnected-(J8-Pad7)")
			(pinfunction "NC")
			(pintype "no_connect")
		)
		(pad "8" connect circle
			(at 0 0.635 270)
			(size 0.7874 0.7874)
			(layers "B.Cu" "B.Mask")
			(net 352 "/X710 flash memory/FLASH.MOSI")
			(pinfunction "SPI_MOSI")
			(pintype "passive")
		)
		(pad "9" connect circle
			(at -1.27 0.635 270)
			(size 0.7874 0.7874)
			(layers "B.Cu" "B.Mask")
			(net 23 "GND")
			(pinfunction "GND")
			(pintype "passive")
		)
		(pad "10" connect circle
			(at -2.54 0.635 270)
			(size 0.7874 0.7874)
			(layers "B.Cu" "B.Mask")
			(net 424 "unconnected-(J8-Pad10)")
			(pinfunction "SPI_NC")
			(pintype "passive+no_connect")
		)
	)
	(footprint "antmicro-footprints:R_0402_1005Metric"
		(layer "B.Cu")
		(at 136.500001 116.125001)
		(descr "Resistor SMD 0402")
		(tags "resistor SMD 0402")
		(property "Reference" "R47"
			(at 19.525001 -7.450001 180)
			(layer "B.SilkS")
			(effects
				(font
					(size 0.7 0.7)
					(thickness 0.15)
				)
				(justify mirror)
			)
		)
		(property "Value" "R_100k_0402"
			(at -1.011843 -1.772047 180)
			(layer "B.Fab")
			(effects
				(font
					(size 0.7 0.7)
					(thickness 0.15)
				)
				(justify left bottom mirror)
			)
		)
		(property "Datasheet" "https://www.bourns.com/docs/product-datasheets/cr.pdf"
			(at 0 0 180)
			(layer "B.Fab")
			(hide yes)
			(effects
				(font
					(size 1.27 1.27)
					(thickness 0.15)
				)
				(justify mirror)
			)
		)
		(property "Description" "SMD Chip Resistor, 100 kohm, ± 1%, 62.5 mW, 0402 [1005 Metric], Thick Film, General Purpose"
			(at 0 0 180)
			(layer "B.Fab")
			(hide yes)
			(effects
				(font
					(size 1.27 1.27)
					(thickness 0.15)
				)
				(justify mirror)
			)
		)
		(property "MPN" "CR0402-FX-1003GLF"
			(at 0 0 0)
			(unlocked yes)
			(layer "B.Fab")
			(hide yes)
			(effects
				(font
					(size 1 1)
					(thickness 0.15)
				)
				(justify mirror)
			)
		)
		(property "Manufacturer" "Bourns"
			(at 0 0 0)
			(unlocked yes)
			(layer "B.Fab")
			(hide yes)
			(effects
				(font
					(size 1 1)
					(thickness 0.15)
				)
				(justify mirror)
			)
		)
		(property "License" "Apache-2.0"
			(at 0 0 0)
			(unlocked yes)
			(layer "B.Fab")
			(hide yes)
			(effects
				(font
					(size 1 1)
					(thickness 0.15)
				)
				(justify mirror)
			)
		)
		(property "Val" "100k"
			(at 0 0 0)
			(unlocked yes)
			(layer "B.Fab")
			(hide yes)
			(effects
				(font
					(size 1 1)
					(thickness 0.15)
				)
				(justify mirror)
			)
		)
		(property "Tolerance" "1%"
			(at 0 0 0)
			(unlocked yes)
			(layer "B.Fab")
			(hide yes)
			(effects
				(font
					(size 1 1)
					(thickness 0.15)
				)
				(justify mirror)
			)
		)
		(property "Author" "Antmicro"
			(at 0 0 0)
			(unlocked yes)
			(layer "B.Fab")
			(hide yes)
			(effects
				(font
					(size 1 1)
					(thickness 0.15)
				)
				(justify mirror)
			)
		)
		(sheetname "/TB Controller/")
		(sheetfile "tb.kicad_sch")
		(attr smd)
		(fp_rect
			(start -0.925 0.47)
			(end 0.925 -0.47)
			(stroke
				(width 0.05)
				(type default)
			)
			(fill no)
			(layer "B.CrtYd")
		)
		(fp_rect
			(start -0.5 0.25)
			(end 0.5 -0.25)
			(stroke
				(width 0.15)
				(type solid)
			)
			(fill no)
			(layer "B.Fab")
		)
		(fp_text user "${REFERENCE}"
			(at -0.95 -3.168 180)
			(layer "B.Fab")
			(effects
				(font
					(size 0.7 0.7)
					(thickness 0.15)
				)
				(justify left bottom mirror)
			)
		)
		(fp_text user "License: Apache-2.0"
			(at -0.95 -5.169 180)
			(layer "B.Fab")
			(effects
				(font
					(size 0.7 0.7)
					(thickness 0.15)
				)
				(justify left bottom mirror)
			)
		)
		(fp_text user "Author: Antmicro"
			(at -0.95 -4.169 180)
			(layer "B.Fab")
			(effects
				(font
					(size 0.7 0.7)
					(thickness 0.15)
				)
				(justify left bottom mirror)
			)
		)
		(pad "1" smd roundrect
			(at -0.48 0)
			(size 0.59 0.64)
			(layers "B.Cu" "B.Mask" "B.Paste")
			(roundrect_rratio 0.25)
			(net 190 "Net-(U4C-GPIO_7)")
			(pintype "passive")
		)
		(pad "2" smd roundrect
			(at 0.48 0)
			(size 0.59 0.64)
			(layers "B.Cu" "B.Mask" "B.Paste")
			(roundrect_rratio 0.25)
			(net 23 "GND")
			(pintype "passive")
		)
	)
	(footprint "antmicro-footprints:C_0402_1005Metric"
		(layer "B.Cu")
		(at 156.081866 90.485117 180)
		(descr "Capacitor SMD 0402")
		(tags "capacitor SMD 0402")
		(property "Reference" "C174"
			(at -18.868134 -10.514883 0)
			(layer "B.SilkS")
			(effects
				(font
					(size 0.7 0.7)
					(thickness 0.15)
				)
				(justify mirror)
			)
		)
		(property "Value" "C_1u_25V_0402"
			(at -1.022927 -2.155213 0)
			(layer "B.Fab")
			(effects
				(font
					(size 0.7 0.7)
					(thickness 0.15)
				)
				(justify left bottom mirror)
			)
		)
		(property "Datasheet" "https://www.murata.com/products/productdetail?partno=GRM155R61E105KE11%23"
			(at 0 0 0)
			(layer "B.Fab")
			(hide yes)
			(effects
				(font
					(size 1.27 1.27)
					(thickness 0.15)
				)
				(justify mirror)
			)
		)
		(property "Description" "SMD Multilayer Ceramic Capacitor, 1 µF, 25 V, 0402 [1005 Metric], ± 10%, X5R, GRM Series"
			(at 0 0 0)
			(layer "B.Fab")
			(hide yes)
			(effects
				(font
					(size 1.27 1.27)
					(thickness 0.15)
				)
				(justify mirror)
			)
		)
		(property "MPN" "GRM155R61E105KE11J"
			(at 0 0 180)
			(unlocked yes)
			(layer "B.Fab")
			(hide yes)
			(effects
				(font
					(size 1 1)
					(thickness 0.15)
				)
				(justify mirror)
			)
		)
		(property "Manufacturer" "Murata"
			(at 0 0 180)
			(unlocked yes)
			(layer "B.Fab")
			(hide yes)
			(effects
				(font
					(size 1 1)
					(thickness 0.15)
				)
				(justify mirror)
			)
		)
		(property "License" "Apache-2.0"
			(at 0 0 180)
			(unlocked yes)
			(layer "B.Fab")
			(hide yes)
			(effects
				(font
					(size 1 1)
					(thickness 0.15)
				)
				(justify mirror)
			)
		)
		(property "Author" "Antmicro"
			(at 0 0 180)
			(unlocked yes)
			(layer "B.Fab")
			(hide yes)
			(effects
				(font
					(size 1 1)
					(thickness 0.15)
				)
				(justify mirror)
			)
		)
		(property "Val" "1u"
			(at 0 0 180)
			(unlocked yes)
			(layer "B.Fab")
			(hide yes)
			(effects
				(font
					(size 1 1)
					(thickness 0.15)
				)
				(justify mirror)
			)
		)
		(property "Voltage" "25V"
			(at 0 0 180)
			(unlocked yes)
			(layer "B.Fab")
			(hide yes)
			(effects
				(font
					(size 1 1)
					(thickness 0.15)
				)
				(justify mirror)
			)
		)
		(property "Dielectric" "X5R"
			(at 0 0 180)
			(unlocked yes)
			(layer "B.Fab")
			(hide yes)
			(effects
				(font
					(size 1 1)
					(thickness 0.15)
				)
				(justify mirror)
			)
		)
		(sheetname "/X710-AT2 power/")
		(sheetfile "x710-at2-power.kicad_sch")
		(attr smd)
		(fp_rect
			(start -0.925 0.47)
			(end 0.925 -0.47)
			(stroke
				(width 0.05)
				(type default)
			)
			(fill no)
			(layer "B.CrtYd")
		)
		(fp_line
			(start 0.504 0.25)
			(end 0.504 -0.248)
			(stroke
				(width 0.15)
				(type solid)
			)
			(layer "B.Fab")
		)
		(fp_line
			(start 0.504 -0.248)
			(end -0.494 -0.248)
			(stroke
				(width 0.15)
				(type solid)
			)
			(layer "B.Fab")
		)
		(fp_line
			(start -0.494 0.25)
			(end 0.504 0.25)
			(stroke
				(width 0.15)
				(type solid)
			)
			(layer "B.Fab")
		)
		(fp_line
			(start -0.494 -0.248)
			(end -0.494 0.25)
			(stroke
				(width 0.15)
				(type solid)
			)
			(layer "B.Fab")
		)
		(fp_text user "License: Apache-2.0"
			(at -0.939 -5.799 0)
			(layer "B.Fab")
			(effects
				(font
					(size 0.7 0.7)
					(thickness 0.15)
				)
				(justify left bottom mirror)
			)
		)
		(fp_text user "${REFERENCE}"
			(at -0.939 -4.599 0)
			(layer "B.Fab")
			(effects
				(font
					(size 0.7 0.7)
					(thickness 0.15)
				)
				(justify left bottom mirror)
			)
		)
		(fp_text user "Author: Antmicro"
			(at -0.939 -3.399 0)
			(layer "B.Fab")
			(effects
				(font
					(size 0.7 0.7)
					(thickness 0.15)
				)
				(justify left bottom mirror)
			)
		)
		(pad "1" smd roundrect
			(at -0.48 0 180)
			(size 0.59 0.64)
			(layers "B.Cu" "B.Mask" "B.Paste")
			(roundrect_rratio 0.25)
			(net 23 "GND")
			(pintype "passive")
		)
		(pad "2" smd roundrect
			(at 0.48 0 180)
			(size 0.59 0.64)
			(layers "B.Cu" "B.Mask" "B.Paste")
			(roundrect_rratio 0.25)
			(net 22 "PLL_VDD")
			(pintype "passive")
		)
	)
	(footprint "antmicro-footprints:R_0402_1005Metric"
		(layer "B.Cu")
		(at 133.75 114.9426)
		(descr "Resistor SMD 0402")
		(tags "resistor SMD 0402")
		(property "Reference" "R42"
			(at 19.525001 -7.450001 180)
			(layer "B.SilkS")
			(effects
				(font
					(size 0.7 0.7)
					(thickness 0.15)
				)
				(justify mirror)
			)
		)
		(property "Value" "R_14k_0402"
			(at -1.011843 -1.772047 180)
			(layer "B.Fab")
			(effects
				(font
					(size 0.7 0.7)
					(thickness 0.15)
				)
				(justify left bottom mirror)
			)
		)
		(property "Datasheet" "https://www.bourns.com/docs/product-datasheets/cr.pdf"
			(at 0 0 180)
			(layer "B.Fab")
			(hide yes)
			(effects
				(font
					(size 1.27 1.27)
					(thickness 0.15)
				)
				(justify mirror)
			)
		)
		(property "Description" "SMD Chip Resistor, 14 kohm, ± 1%, 100 mW, 0402 [1005 Metric], Thick Film, Precision"
			(at 0 0 180)
			(layer "B.Fab")
			(hide yes)
			(effects
				(font
					(size 1.27 1.27)
					(thickness 0.15)
				)
				(justify mirror)
			)
		)
		(property "MPN" "CR0402-FX-1402GLF"
			(at 0 0 0)
			(unlocked yes)
			(layer "B.Fab")
			(hide yes)
			(effects
				(font
					(size 1 1)
					(thickness 0.15)
				)
				(justify mirror)
			)
		)
		(property "Manufacturer" "Bourns"
			(at 0 0 0)
			(unlocked yes)
			(layer "B.Fab")
			(hide yes)
			(effects
				(font
					(size 1 1)
					(thickness 0.15)
				)
				(justify mirror)
			)
		)
		(property "License" "Apache-2.0"
			(at 0 0 0)
			(unlocked yes)
			(layer "B.Fab")
			(hide yes)
			(effects
				(font
					(size 1 1)
					(thickness 0.15)
				)
				(justify mirror)
			)
		)
		(property "Val" "14k"
			(at 0 0 0)
			(unlocked yes)
			(layer "B.Fab")
			(hide yes)
			(effects
				(font
					(size 1 1)
					(thickness 0.15)
				)
				(justify mirror)
			)
		)
		(property "Tolerance" "1%"
			(at 0 0 0)
			(unlocked yes)
			(layer "B.Fab")
			(hide yes)
			(effects
				(font
					(size 1 1)
					(thickness 0.15)
				)
				(justify mirror)
			)
		)
		(property "Author" "Antmicro"
			(at 0 0 0)
			(unlocked yes)
			(layer "B.Fab")
			(hide yes)
			(effects
				(font
					(size 1 1)
					(thickness 0.15)
				)
				(justify mirror)
			)
		)
		(sheetname "/TB Controller/")
		(sheetfile "tb.kicad_sch")
		(attr smd dnp)
		(fp_rect
			(start -0.925 0.47)
			(end 0.925 -0.47)
			(stroke
				(width 0.05)
				(type default)
			)
			(fill no)
			(layer "B.CrtYd")
		)
		(fp_rect
			(start -0.5 0.25)
			(end 0.5 -0.25)
			(stroke
				(width 0.15)
				(type solid)
			)
			(fill no)
			(layer "B.Fab")
		)
		(fp_text user "Author: Antmicro"
			(at -0.95 -4.169 180)
			(layer "B.Fab")
			(effects
				(font
					(size 0.7 0.7)
					(thickness 0.15)
				)
				(justify left bottom mirror)
			)
		)
		(fp_text user "${REFERENCE}"
			(at -0.95 -3.168 180)
			(layer "B.Fab")
			(effects
				(font
					(size 0.7 0.7)
					(thickness 0.15)
				)
				(justify left bottom mirror)
			)
		)
		(fp_text user "License: Apache-2.0"
			(at -0.95 -5.169 180)
			(layer "B.Fab")
			(effects
				(font
					(size 0.7 0.7)
					(thickness 0.15)
				)
				(justify left bottom mirror)
			)
		)
		(pad "1" smd roundrect
			(at -0.48 0)
			(size 0.59 0.64)
			(layers "B.Cu" "B.Mask" "B.Paste")
			(roundrect_rratio 0.25)
			(net 185 "Net-(U4C-DPSRC_RBIAS)")
			(pintype "passive")
		)
		(pad "2" smd roundrect
			(at 0.48 0)
			(size 0.59 0.64)
			(layers "B.Cu" "B.Mask" "B.Paste")
			(roundrect_rratio 0.25)
			(net 23 "GND")
			(pintype "passive")
		)
	)
)
